FILE_TYPE = CONNECTIVITY;
{Allegro Design Entry HDL 17.2-2016 S081 (4005846) 1/11/2022}
"PAGE_NUMBER" = 269;
0"NC";
END.
